(kicad_pcb
	(version 20260206)
	(generator "pcbnew")
	(generator_version "10.0")
	(general
		(thickness 1.6)
		(legacy_teardrops no)
	)
	(paper "A4")
	(title_block
		(title "v1-pdb — T6M_PDB_D_0927_0900.brd")
		(comment 1 "Open CloudServer (Microsoft) / footprint 321 of 321 (J9), pads 1-46 of 46")
	)
	(layers
		(0 "F.Cu" signal "TOP")
		(4 "In1.Cu" signal "GND")
		(6 "In2.Cu" signal "IN1")
		(8 "In3.Cu" signal "VCC")
		(10 "In4.Cu" signal "VCC1")
		(12 "In5.Cu" signal "IN2")
		(14 "In6.Cu" signal "GND1")
		(2 "B.Cu" signal "BOTTOM")
		(9 "F.Adhes" user "F.Adhesive")
		(11 "B.Adhes" user "B.Adhesive")
		(13 "F.Paste" user "Package Geometry/Pastemask Top")
		(15 "B.Paste" user "Package Geometry/Pastemask Bottom")
		(5 "F.SilkS" user "Ref Des/Silkscreen Top")
		(7 "B.SilkS" user "Ref Des/Silkscreen Bottom")
		(1 "F.Mask" user "Board Geometry/Soldermask Top")
		(3 "B.Mask" user "Board Geometry/Soldermask Bottom")
		(17 "Dwgs.User" user "User.Drawings")
		(19 "Cmts.User" user "User.Comments")
		(21 "Eco1.User" user "User.Eco1")
		(23 "Eco2.User" user "User.Eco2")
		(25 "Edge.Cuts" user "Board Geometry/Outline")
		(27 "Margin" user)
		(31 "F.CrtYd" user "Package Geometry/Place Bound Top")
		(29 "B.CrtYd" user "Package Geometry/Place Bound Bottom")
		(35 "F.Fab" user "Ref Des/Assembly Top")
		(33 "B.Fab" user "Ref Des/Assembly Bottom")
	)
	(footprint ""
		(layer "B.Cu")
		(at 44.03979 -97.16008 90)
		(property "Reference" "J9"
			(at 6.238748 -5.04063 0)
			(unlocked yes)
			(layer "B.SilkS")
			(effects
				(font
					(size 0.7874 0.5842)
					(thickness 0.1524)
				)
				(justify left mirror)
			)
		)
		(property "Value" ""
			(at 0 0 90)
			(layer "B.Fab")
			(effects
				(font
					(size 1.27 1.27)
				)
				(justify mirror)
			)
		)
		(duplicate_pad_numbers_are_jumpers no)
		(pad "" np_thru_hole circle
			(at -1.35001 -2.54)
			(size 2.5146 2.5146)
			(drill 2.5146)
			(layers "*.Cu" "*.Mask")
			(clearance 0.381)
			(thermal_gap 0.381)
		)
		(pad "" np_thru_hole circle
			(at 0 50.8)
			(size 2.5146 2.5146)
			(drill 2.5146)
			(layers "*.Cu" "*.Mask")
			(clearance 0.381)
			(thermal_gap 0.381)
		)
		(pad "P1" thru_hole rect
			(at 0 0)
			(size 1.1684 1.1684)
			(drill 0.762)
			(layers "*.Cu" "*.Mask")
			(remove_unused_layers no)
			(net "GND")
			(clearance 0.0508)
			(padstack
				(mode front_inner_back)
				(layer "Inner"
					(shape circle)
					(size 1.1684 1.1684)
					(clearance 0.0508)
				)
				(layer "B.Cu"
					(shape rect)
					(size 1.1684 1.1684)
					(thermal_gap 0.0508)
					(clearance 0.0508)
				)
			)
		)
		(pad "P2" thru_hole circle
			(at 0 2.54)
			(size 1.1684 1.1684)
			(drill 0.762)
			(layers "*.Cu" "*.Mask")
			(remove_unused_layers no)
			(net "GND")
			(clearance 0.0508)
			(thermal_gap 0.0508)
		)
		(pad "P3" thru_hole circle
			(at 0 5.08)
			(size 1.1684 1.1684)
			(drill 0.762)
			(layers "*.Cu" "*.Mask")
			(remove_unused_layers no)
			(net "GND")
			(clearance 0.0508)
			(thermal_gap 0.0508)
		)
		(pad "P4" thru_hole circle
			(at 0 7.62)
			(size 1.1684 1.1684)
			(drill 0.762)
			(layers "*.Cu" "*.Mask")
			(remove_unused_layers no)
			(net "GND")
			(clearance 0.0508)
			(thermal_gap 0.0508)
		)
		(pad "P5" thru_hole circle
			(at 0 10.16)
			(size 1.1684 1.1684)
			(drill 0.762)
			(layers "*.Cu" "*.Mask")
			(remove_unused_layers no)
			(net "GND")
			(clearance 0.0508)
			(thermal_gap 0.0508)
		)
		(pad "P6" thru_hole circle
			(at 0 12.7)
			(size 1.1684 1.1684)
			(drill 0.762)
			(layers "*.Cu" "*.Mask")
			(remove_unused_layers no)
			(net "GND")
			(clearance 0.0508)
			(thermal_gap 0.0508)
		)
		(pad "P7" thru_hole circle
			(at 0 15.24)
			(size 1.1684 1.1684)
			(drill 0.762)
			(layers "*.Cu" "*.Mask")
			(remove_unused_layers no)
			(net "GND")
			(clearance 0.0508)
			(thermal_gap 0.0508)
		)
		(pad "P8" thru_hole circle
			(at 0 17.78)
			(size 1.1684 1.1684)
			(drill 0.762)
			(layers "*.Cu" "*.Mask")
			(remove_unused_layers no)
			(net "GND")
			(clearance 0.0508)
			(thermal_gap 0.0508)
		)
		(pad "P9" thru_hole circle
			(at 0 20.32)
			(size 1.1684 1.1684)
			(drill 0.762)
			(layers "*.Cu" "*.Mask")
			(remove_unused_layers no)
			(net "P12V")
			(clearance 0.0508)
			(thermal_gap 0.0508)
		)
		(pad "P10" thru_hole circle
			(at 0 22.86)
			(size 1.1684 1.1684)
			(drill 0.762)
			(layers "*.Cu" "*.Mask")
			(remove_unused_layers no)
			(net "P12V")
			(clearance 0.0508)
			(thermal_gap 0.0508)
		)
		(pad "P11" thru_hole circle
			(at 0 25.4)
			(size 1.1684 1.1684)
			(drill 0.762)
			(layers "*.Cu" "*.Mask")
			(remove_unused_layers no)
			(net "P12V")
			(clearance 0.0508)
			(thermal_gap 0.0508)
		)
		(pad "P12" thru_hole circle
			(at 0 27.94)
			(size 1.1684 1.1684)
			(drill 0.762)
			(layers "*.Cu" "*.Mask")
			(remove_unused_layers no)
			(net "P12V")
			(clearance 0.0508)
			(thermal_gap 0.0508)
		)
		(pad "P13" thru_hole circle
			(at 0 30.48)
			(size 1.1684 1.1684)
			(drill 0.762)
			(layers "*.Cu" "*.Mask")
			(remove_unused_layers no)
			(net "P12V")
			(clearance 0.0508)
			(thermal_gap 0.0508)
		)
		(pad "P14" thru_hole circle
			(at 0 33.02)
			(size 1.1684 1.1684)
			(drill 0.762)
			(layers "*.Cu" "*.Mask")
			(remove_unused_layers no)
			(net "P12V")
			(clearance 0.0508)
			(thermal_gap 0.0508)
		)
		(pad "P15" thru_hole circle
			(at 0 35.56)
			(size 1.1684 1.1684)
			(drill 0.762)
			(layers "*.Cu" "*.Mask")
			(remove_unused_layers no)
			(net "P12V")
			(clearance 0.0508)
			(thermal_gap 0.0508)
		)
		(pad "P16" thru_hole circle
			(at 0 38.1)
			(size 1.1684 1.1684)
			(drill 0.762)
			(layers "*.Cu" "*.Mask")
			(remove_unused_layers no)
			(net "P12V")
			(clearance 0.0508)
			(thermal_gap 0.0508)
		)
		(pad "P17" thru_hole circle
			(at -2.70002 38.1)
			(size 1.1684 1.1684)
			(drill 0.762)
			(layers "*.Cu" "*.Mask")
			(remove_unused_layers no)
			(net "P12V")
			(clearance 0.0508)
			(thermal_gap 0.0508)
		)
		(pad "P18" thru_hole circle
			(at -2.70002 35.56)
			(size 1.1684 1.1684)
			(drill 0.762)
			(layers "*.Cu" "*.Mask")
			(remove_unused_layers no)
			(net "P12V")
			(clearance 0.0508)
			(thermal_gap 0.0508)
		)
		(pad "P19" thru_hole circle
			(at -2.70002 33.02)
			(size 1.1684 1.1684)
			(drill 0.762)
			(layers "*.Cu" "*.Mask")
			(remove_unused_layers no)
			(net "P12V")
			(clearance 0.0508)
			(thermal_gap 0.0508)
		)
		(pad "P20" thru_hole circle
			(at -2.70002 30.48)
			(size 1.1684 1.1684)
			(drill 0.762)
			(layers "*.Cu" "*.Mask")
			(remove_unused_layers no)
			(net "P12V")
			(clearance 0.0508)
			(thermal_gap 0.0508)
		)
		(pad "P21" thru_hole circle
			(at -2.70002 27.94)
			(size 1.1684 1.1684)
			(drill 0.762)
			(layers "*.Cu" "*.Mask")
			(remove_unused_layers no)
			(net "P12V")
			(clearance 0.0508)
			(thermal_gap 0.0508)
		)
		(pad "P22" thru_hole circle
			(at -2.70002 25.4)
			(size 1.1684 1.1684)
			(drill 0.762)
			(layers "*.Cu" "*.Mask")
			(remove_unused_layers no)
			(net "P12V")
			(clearance 0.0508)
			(thermal_gap 0.0508)
		)
		(pad "P23" thru_hole circle
			(at -2.70002 22.86)
			(size 1.1684 1.1684)
			(drill 0.762)
			(layers "*.Cu" "*.Mask")
			(remove_unused_layers no)
			(net "P12V")
			(clearance 0.0508)
			(thermal_gap 0.0508)
		)
		(pad "P24" thru_hole circle
			(at -2.70002 20.32)
			(size 1.1684 1.1684)
			(drill 0.762)
			(layers "*.Cu" "*.Mask")
			(remove_unused_layers no)
			(net "P12V")
			(clearance 0.0508)
			(thermal_gap 0.0508)
		)
		(pad "P25" thru_hole circle
			(at -2.70002 17.78)
			(size 1.1684 1.1684)
			(drill 0.762)
			(layers "*.Cu" "*.Mask")
			(remove_unused_layers no)
			(net "GND")
			(clearance 0.0508)
			(thermal_gap 0.0508)
		)
		(pad "P26" thru_hole circle
			(at -2.70002 15.24)
			(size 1.1684 1.1684)
			(drill 0.762)
			(layers "*.Cu" "*.Mask")
			(remove_unused_layers no)
			(net "GND")
			(clearance 0.0508)
			(thermal_gap 0.0508)
		)
		(pad "P27" thru_hole circle
			(at -2.70002 12.7)
			(size 1.1684 1.1684)
			(drill 0.762)
			(layers "*.Cu" "*.Mask")
			(remove_unused_layers no)
			(net "GND")
			(clearance 0.0508)
			(thermal_gap 0.0508)
		)
		(pad "P28" thru_hole circle
			(at -2.70002 10.16)
			(size 1.1684 1.1684)
			(drill 0.762)
			(layers "*.Cu" "*.Mask")
			(remove_unused_layers no)
			(net "GND")
			(clearance 0.0508)
			(thermal_gap 0.0508)
		)
		(pad "P29" thru_hole circle
			(at -2.70002 7.62)
			(size 1.1684 1.1684)
			(drill 0.762)
			(layers "*.Cu" "*.Mask")
			(remove_unused_layers no)
			(net "GND")
			(clearance 0.0508)
			(thermal_gap 0.0508)
		)
		(pad "P30" thru_hole circle
			(at -2.70002 5.08)
			(size 1.1684 1.1684)
			(drill 0.762)
			(layers "*.Cu" "*.Mask")
			(remove_unused_layers no)
			(net "GND")
			(clearance 0.0508)
			(thermal_gap 0.0508)
		)
		(pad "P31" thru_hole circle
			(at -2.70002 2.54)
			(size 1.1684 1.1684)
			(drill 0.762)
			(layers "*.Cu" "*.Mask")
			(remove_unused_layers no)
			(net "GND")
			(clearance 0.0508)
			(thermal_gap 0.0508)
		)
		(pad "P32" thru_hole circle
			(at -2.70002 0)
			(size 1.1684 1.1684)
			(drill 0.762)
			(layers "*.Cu" "*.Mask")
			(remove_unused_layers no)
			(net "GND")
			(clearance 0.0508)
			(thermal_gap 0.0508)
		)
		(pad "S1" thru_hole circle
			(at 0.55499 41.60012)
			(size 1.1684 1.1684)
			(drill 0.762)
			(layers "*.Cu" "*.Mask")
			(remove_unused_layers no)
			(net "T3_BLAD1_TXD")
			(clearance 0.0508)
			(thermal_gap 0.0508)
		)
		(pad "S2" thru_hole circle
			(at -0.71501 42.87012)
			(size 1.1684 1.1684)
			(drill 0.762)
			(layers "*.Cu" "*.Mask")
			(remove_unused_layers no)
			(net "T3_BLAD1_RXD")
			(clearance 0.0508)
			(thermal_gap 0.0508)
		)
		(pad "S3" thru_hole circle
			(at 0.55499 44.14012)
			(size 1.1684 1.1684)
			(drill 0.762)
			(layers "*.Cu" "*.Mask")
			(remove_unused_layers no)
			(net "T3_BLAD1_EN")
			(clearance 0.0508)
			(thermal_gap 0.0508)
		)
		(pad "S4" thru_hole circle
			(at -0.71501 45.41012)
			(size 1.1684 1.1684)
			(drill 0.762)
			(layers "*.Cu" "*.Mask")
			(remove_unused_layers no)
			(net "T3_BLAD2_EN")
			(clearance 0.0508)
			(thermal_gap 0.0508)
		)
		(pad "S5" thru_hole circle
			(at 0.55499 46.68012)
			(size 1.1684 1.1684)
			(drill 0.762)
			(layers "*.Cu" "*.Mask")
			(remove_unused_layers no)
			(net "T3_BLAD2_TXD")
			(clearance 0.0508)
			(thermal_gap 0.0508)
		)
		(pad "S6" thru_hole circle
			(at -0.71501 47.95012)
			(size 1.1684 1.1684)
			(drill 0.762)
			(layers "*.Cu" "*.Mask")
			(remove_unused_layers no)
			(net "T3_BLAD2_RXD")
			(clearance 0.0508)
			(thermal_gap 0.0508)
		)
		(pad "S7" thru_hole circle
			(at -3.25501 47.95012)
			(size 1.1684 1.1684)
			(drill 0.762)
			(layers "*.Cu" "*.Mask")
			(remove_unused_layers no)
			(net "T3_BLAD4_RXD")
			(clearance 0.0508)
			(thermal_gap 0.0508)
		)
		(pad "S8" thru_hole circle
			(at -1.98501 46.68012)
			(size 1.1684 1.1684)
			(drill 0.762)
			(layers "*.Cu" "*.Mask")
			(remove_unused_layers no)
			(net "T3_BLAD4_TXD")
			(clearance 0.0508)
			(thermal_gap 0.0508)
		)
		(pad "S9" thru_hole circle
			(at -3.25501 45.41012)
			(size 1.1684 1.1684)
			(drill 0.762)
			(layers "*.Cu" "*.Mask")
			(remove_unused_layers no)
			(net "T3_BLAD4_EN")
			(clearance 0.0508)
			(thermal_gap 0.0508)
		)
		(pad "S10" thru_hole circle
			(at -1.98501 44.14012)
			(size 1.1684 1.1684)
			(drill 0.762)
			(layers "*.Cu" "*.Mask")
			(remove_unused_layers no)
			(net "T3_BLAD3_EN")
			(clearance 0.0508)
			(thermal_gap 0.0508)
		)
		(pad "S11" thru_hole circle
			(at -3.25501 42.87012)
			(size 1.1684 1.1684)
			(drill 0.762)
			(layers "*.Cu" "*.Mask")
			(remove_unused_layers no)
			(net "T3_BLAD3_RXD")
			(clearance 0.0508)
			(thermal_gap 0.0508)
		)
		(pad "S12" thru_hole circle
			(at -1.98501 41.60012)
			(size 1.1684 1.1684)
			(drill 0.762)
			(layers "*.Cu" "*.Mask")
			(remove_unused_layers no)
			(net "T3_BLAD3_TXD")
			(clearance 0.0508)
			(thermal_gap 0.0508)
		)
	)
)
